# S9S_MB_2U (Grand Teton) — schematic parts with pin connectivity, parts 1668–1755 of 6093; source: Cadence DE-HDL packaged netlist (pstxprt.dat, pstxnet.dat, pstchip.dat)

J112  CONN160_10131762101LF  CONN160_10131762-101LF IO  pkg HSD_F160D8_P2W1-2_RDH  page 143
  A1  A1  BI  = RST_PERST_2_SWB_BUF_N
  A2  A2  BI  = GND
  A3  A3  BI  = HGX_DETECT_N_ISO
  A4  A4  BI  = GND
  A5  A5  BI  = RST_PERST_1_SWB_BUF_N
  A6  A6  BI  = GND
  A7  A7  BI  = PRSNT_SWB_N
  A8  A8  BI  = GND
  B1  B1  BI  = GND
  B2  B2  BI  = P5E_CPU1_PE0_RX_DN<14>
  B3  B3  BI  = GND
  B4  B4  BI  = P5E_CPU1_PE0_RX_DN<12>
  B5  B5  BI  = GND
  B6  B6  BI  = P5E_CPU1_PE0_RX_DN<10>
  B7  B7  BI  = GND
  B8  B8  BI  = P5E_CPU1_PE0_RX_DN<8>
  C1  C1  BI  = P5E_CPU1_PE0_RX_DN<15>
  C2  C2  BI  = P5E_CPU1_PE0_RX_DP<14>
  C3  C3  BI  = P5E_CPU1_PE0_RX_DN<13>
  C4  C4  BI  = P5E_CPU1_PE0_RX_DP<12>
  C5  C5  BI  = P5E_CPU1_PE0_RX_DP<11>
  C6  C6  BI  = P5E_CPU1_PE0_RX_DP<10>
  C7  C7  BI  = P5E_CPU1_PE0_RX_DN<9>
  C8  C8  BI  = P5E_CPU1_PE0_RX_DP<8>
  D1  D1  BI  = P5E_CPU1_PE0_RX_DP<15>
  D2  D2  BI  = GND
  D3  D3  BI  = P5E_CPU1_PE0_RX_DP<13>
  D4  D4  BI  = GND
  D5  D5  BI  = P5E_CPU1_PE0_RX_DN<11>
  D6  D6  BI  = GND
  D7  D7  BI  = P5E_CPU1_PE0_RX_DP<9>
  D8  D8  BI  = GND
  E1  E1  BI  = GND
  E2  E2  BI  = P5E_CPU1_PE4_RX_DP<1>
  E3  E3  BI  = GND
  E4  E4  BI  = P5E_CPU1_PE4_RX_DP<3>
  E5  E5  BI  = GND
  E6  E6  BI  = P5E_CPU1_PE4_RX_DP<5>
  E7  E7  BI  = GND
  E8  E8  BI  = P5E_CPU1_PE4_RX_DP<7>
  F1  F1  BI  = P5E_CPU1_PE4_RX_DN<0>
  F2  F2  BI  = P5E_CPU1_PE4_RX_DN<1>
  F3  F3  BI  = P5E_CPU1_PE4_RX_DN<2>
  F4  F4  BI  = P5E_CPU1_PE4_RX_DN<3>
  F5  F5  BI  = P5E_CPU1_PE4_RX_DN<4>
  F6  F6  BI  = P5E_CPU1_PE4_RX_DN<5>
  F7  F7  BI  = P5E_CPU1_PE4_RX_DN<6>
  F8  F8  BI  = P5E_CPU1_PE4_RX_DN<7>
  G1  G1  BI  = P5E_CPU1_PE4_RX_DP<0>
  G2  G2  BI  = GND
  G3  G3  BI  = P5E_CPU1_PE4_RX_DP<2>
  G4  G4  BI  = GND
  G5  G5  BI  = P5E_CPU1_PE4_RX_DP<4>
  G6  G6  BI  = GND
  G7  G7  BI  = P5E_CPU1_PE4_RX_DP<6>
  G8  G8  BI  = GND
  H1  H1  BI  = GND
  H2  H2  BI  = P5E_CPU1_PE0_TX_C_DN<14>
  H3  H3  BI  = GND
  H4  H4  BI  = P5E_CPU1_PE0_TX_C_DN<12>
  H5  H5  BI  = GND
  H6  H6  BI  = P5E_CPU1_PE0_TX_C_DN<10>
  H7  H7  BI  = GND
  H8  H8  BI  = P5E_CPU1_PE0_TX_C_DN<8>
  I1  I1  BI  = P5E_CPU1_PE0_TX_C_DN<15>
  I2  I2  BI  = P5E_CPU1_PE0_TX_C_DP<14>
  I3  I3  BI  = P5E_CPU1_PE0_TX_C_DN<13>
  I4  I4  BI  = P5E_CPU1_PE0_TX_C_DP<12>
  I5  I5  BI  = P5E_CPU1_PE0_TX_C_DN<11>
  I6  I6  BI  = P5E_CPU1_PE0_TX_C_DP<10>
  I7  I7  BI  = P5E_CPU1_PE0_TX_C_DN<9>
  I8  I8  BI  = P5E_CPU1_PE0_TX_C_DP<8>
  J1  J1  BI  = P5E_CPU1_PE0_TX_C_DP<15>
  J2  J2  BI  = GND
  J3  J3  BI  = P5E_CPU1_PE0_TX_C_DP<13>
  J4  J4  BI  = GND
  J5  J5  BI  = P5E_CPU1_PE0_TX_C_DP<11>
  J6  J6  BI  = GND
  J7  J7  BI  = P5E_CPU1_PE0_TX_C_DP<9>
  J8  J8  BI  = GND
  K1  K1  BI  = GND
  K2  K2  BI  = P5E_CPU1_PE4_TX_C_DP<1>
  K3  K3  BI  = GND
  K4  K4  BI  = P5E_CPU1_PE4_TX_C_DN<3>
  K5  K5  BI  = GND
  K6  K6  BI  = P5E_CPU1_PE4_TX_C_DN<5>
  K7  K7  BI  = GND
  K8  K8  BI  = P5E_CPU1_PE4_TX_C_DN<7>
  L1  L1  BI  = P5E_CPU1_PE4_TX_C_DN<0>
  L2  L2  BI  = P5E_CPU1_PE4_TX_C_DN<1>
  L3  L3  BI  = P5E_CPU1_PE4_TX_C_DN<2>
  L4  L4  BI  = P5E_CPU1_PE4_TX_C_DP<3>
  L5  L5  BI  = P5E_CPU1_PE4_TX_C_DN<4>
  L6  L6  BI  = P5E_CPU1_PE4_TX_C_DP<5>
  L7  L7  BI  = P5E_CPU1_PE4_TX_C_DN<6>
  L8  L8  BI  = P5E_CPU1_PE4_TX_C_DP<7>
  M1  M1  BI  = P5E_CPU1_PE4_TX_C_DP<0>
  M2  M2  BI  = GND
  M3  M3  BI  = P5E_CPU1_PE4_TX_C_DP<2>
  M4  M4  BI  = GND
  M5  M5  BI  = P5E_CPU1_PE4_TX_C_DP<4>
  M6  M6  BI  = GND
  M7  M7  BI  = P5E_CPU1_PE4_TX_C_DP<6>
  M8  M8  BI  = GND
  N1  N1  BI  = GND
  N2  N2  BI  = NC_J112_N2
  N3  N3  BI  = GND
  N4  N4  BI  = CLK_100M_GPU_1_DN
  N5  N5  BI  = GND
  N6  N6  BI  = P2E_MB_BMC_RX_DN<0>
  N7  N7  BI  = GND
  N8  N8  BI  = P3E_PCH_NVS_RX_DN<0>
  O1  O1  BI  = CLK_100M_GPU_2_DN
  O2  O2  BI  = NC_J112_O2
  O3  O3  BI  = CLK_100M_SWB_DN
  O4  O4  BI  = CLK_100M_GPU_1_DP
  O5  O5  BI  = NC_J112_O5
  O6  O6  BI  = P2E_MB_BMC_RX_DP<0>
  O7  O7  BI  = P3E_PCH_NVS_RX_DN<1>
  O8  O8  BI  = P3E_PCH_NVS_RX_DP<0>
  P1  P1  BI  = CLK_100M_GPU_2_DP
  P2  P2  BI  = GND
  P3  P3  BI  = CLK_100M_SWB_DP
  P4  P4  BI  = GND
  P5  P5  BI  = NC_J112_P5
  P6  P6  BI  = GND
  P7  P7  BI  = P3E_PCH_NVS_RX_DP<1>
  P8  P8  BI  = GND
  Q1  Q1  BI  = GND
  Q2  Q2  BI  = CLK_100M_GPU_FPGA_DN
  Q3  Q3  BI  = GND
  Q4  Q4  BI  = SMB_1_BMC_GPU_BUF_SCL
  Q5  Q5  BI  = GND
  Q6  Q6  BI  = P2E_MB_BMC_TX_BUF_C_DN<0>
  Q7  Q7  BI  = GND
  Q8  Q8  BI  = P3E_PCH_NVS_TX_C_DN<0>
  R1  R1  BI  = USB2_HUB_BUF_SWB_DN
  R2  R2  BI  = CLK_100M_GPU_FPGA_DP
  R3  R3  BI  = SMB_2_BMC_GPU_BUF_SCL
  R4  R4  BI  = SMB_1_BMC_GPU_BUF_SDA
  R5  R5  BI  = NC_J112_R5
  R6  R6  BI  = P2E_MB_BMC_TX_BUF_C_DP<0>
  R7  R7  BI  = P3E_PCH_NVS_TX_C_DN<1>
  R8  R8  BI  = P3E_PCH_NVS_TX_C_DP<0>
  S1  S1  BI  = USB2_HUB_BUF_SWB_DP
  S2  S2  BI  = GND
  S3  S3  BI  = SMB_2_BMC_GPU_BUF_SDA
  S4  S4  BI  = GND
  S5  S5  BI  = NC_J112_S5
  S6  S6  BI  = GND
  S7  S7  BI  = P3E_PCH_NVS_TX_C_DP<1>
  S8  S8  BI  = GND
  T1  T1  BI  = GND
  T2  T2  BI  = GPU_FPGA_READY
  T3  T3  BI  = GND
  T4  T4  BI  = GPU_NVS_PWR_BRAKE_N_BUF
  T5  T5  BI  = GND
  T6  T6  BI  = GPU_FPGA_THERM_OVERT_N
  T7  T7  BI  = GND
  T8  T8  BI  = RST_PERST_0_SWB_BUF_N

J114  PICOPROBE_BXA  DELTA-L 4.0 EMPTY  pkg TRIANG_LAUNCH_3PXB  page 308
  1  \1_p\  POWER  = DELTA_L_85_5INCH_IN5_DP
  2  \2_n\  POWER  = DELTA_L_85_5INCH_IN5_DN
  3  \3_g\  POWER  = DELTA_L_GND_1

J115  PICOPROBE_BXA  DELTA-L 4.0 EMPTY  pkg TRIANG_LAUNCH_3PXB  page 308
  1  \1_p\  POWER  = DELTA_L_85_5INCH_IN6_DP
  2  \2_n\  POWER  = DELTA_L_85_5INCH_IN6_DN
  3  \3_g\  POWER  = DELTA_L_GND_1

J116  PICOPROBE_BXA  DELTA-L 4.0 EMPTY  pkg TRIANG_LAUNCH_3PXB  page 308
  1  \1_p\  POWER  = DELTA_L_85_5INCH_IN5_DN
  2  \2_n\  POWER  = DELTA_L_85_5INCH_IN5_DP
  3  \3_g\  POWER  = DELTA_L_GND_1

J117  PICOPROBE_BXA  DELTA-L 4.0 EMPTY  pkg TRIANG_LAUNCH_3PXB  page 308
  1  \1_p\  POWER  = DELTA_L_85_5INCH_IN6_DN
  2  \2_n\  POWER  = DELTA_L_85_5INCH_IN6_DP
  3  \3_g\  POWER  = DELTA_L_GND_1

J118  PICOPROBE_BXA  DELTA-L 4.0 EMPTY  pkg TRIANG_LAUNCH_3PXB  page 308
  1  \1_p\  POWER  = DELTA_L_85_10INCH_IN5_DP
  2  \2_n\  POWER  = DELTA_L_85_10INCH_IN5_DN
  3  \3_g\  POWER  = DELTA_L_GND_1

J119  PICOPROBE_BXA  DELTA-L 4.0 EMPTY  pkg TRIANG_LAUNCH_3PXB  page 308
  1  \1_p\  POWER  = DELTA_L_85_10INCH_IN6_DP
  2  \2_n\  POWER  = DELTA_L_85_10INCH_IN6_DN
  3  \3_g\  POWER  = DELTA_L_GND_1

J120  PICOPROBE_BXA  DELTA-L 4.0 EMPTY  pkg TRIANG_LAUNCH_3PXB  page 308
  1  \1_p\  POWER  = DELTA_L_85_10INCH_IN5_DN
  2  \2_n\  POWER  = DELTA_L_85_10INCH_IN5_DP
  3  \3_g\  POWER  = DELTA_L_GND_1

J121  PICOPROBE_BXA  DELTA-L 4.0 EMPTY  pkg TRIANG_LAUNCH_3PXB  page 308
  1  \1_p\  POWER  = DELTA_L_85_10INCH_IN6_DN
  2  \2_n\  POWER  = DELTA_L_85_10INCH_IN6_DP
  3  \3_g\  POWER  = DELTA_L_GND_1

J122  CONN1_10165288101LF  CONN1_10165288-101LF IO  pkg CON_GUIDE-F1XG  page 311 : SCR_H1 = NC
J123  CONN1_10165288101LF  CONN1_10165288-101LF IO  pkg CON_GUIDE-F1XG  page 311 : SCR_H1 = NC

JP4  CONN3_210HP1030BR1  CONN3_210-HP1-030BR1 EMPTY  pkg HEADER1X3XG  page 183
  1  \1\  BI  = SMB_SML0_3V3AUX_PCH_SCL
  2  \2\  BI  = GND
  3  \3\  BI  = SMB_SML0_3V3AUX_PCH_SDA

JP7  CONN3_210HP1030BR1  CONN3_210-HP1-030BR1 IO  pkg HEADER1X3XG  page 235
  1  \1\  BI  = FM_SMB_PEHPCPU0_PCIE_ALERT_N
  2  \2\  BI  = GND
  3  \3\  BI  = FM_SMB_PEHPCPU1_PCIE_ALERT_N

JP9  CONN3_210HP1030BR1  CONN3_210-HP1-030BR1 EMPTY  pkg HEADER1X3XG  page 183
  1  \1\  BI  = SMB_SML1_PMBUS_3V3AUX_PCH_SCL_1
  2  \2\  BI  = GND
  3  \3\  BI  = SMB_SML1_PMBUS_3V3AUX_PCH_SDA_1

JP10  CONN3_210HP1030BR1  CONN3_210-HP1-030BR1 IO  pkg HEADER1X3XG  page 305
  1  \1\  BI  = SMB_SML1_PMBUS_HSC_MODULE_SCL
  2  \2\  BI  = SMB_SML1_PMBUS_HSC_MODULE_SDA
  3  \3\  BI  = GND

JP15  CONN3_210HP1030BR1  CONN3_210-HP1-030BR1 IO  pkg HEADER1X3XG  page 215
  1  \1\  BI  = PU_FORCE_PWRON
  2  \2\  BI  = FM_FORCE_PWRON_LVC3
  3  \3\  BI  = PD_FORCE_PWRON

JP15_23  TP  NA  pkg TP_BOM ONLY  page 312 : 1 = NC

JP16  CONN3_210HP1030BR1  CONN3_210-HP1-030BR1 IO  pkg HEADER1X3XG  page 248
  1  \1\  BI  = PU_JTAG_SW_PU
  2  \2\  BI  = JTAG_BMC_SW_OE
  3  \3\  BI  = GND

JP16_23  TP  NA  pkg TP_BOM ONLY  page 312 : 1 = NC

JP4003  CONN3_210HP1030BR1  CONN3_210-HP1-030BR1 IO  pkg HEADER1X3XG  page 301
  1  \1\  BI  = NC
  2  \2\  BI  = PDB_PRSNT_N
  3  \3\  BI  = GND

JP4003_12  TP  NA  pkg TP_BOM ONLY  page 312 : 1 = NC
L1  Q_INDUCTOR  FCM2012KF-601T/0.5A IND  pkg SMLF  page 210 : 1 = P3V3_AUX ; 2 = P3V3_AUX_CLK_GEN_VDD_CK440
L2  Q_INDUCTOR  BLM15PX121SN1D/2A EMPTY  pkg SMLF  page 189 : 1 = P1V05_PCH_AUX ; 2 = P1V05_PCH_PLL_AUX
L3  Q_INDUCTOR  BLM18SG331TN1D/1.5A IND  pkg SMLF  page 206 : 1 = P3V3 ; 2 = P3V3_DB2000_VDD
L4  Q_INDUCTOR  BLM18SG331TN1D/1.5A IND  pkg SMLF  page 206 : 1 = P3V3 ; 2 = P3V3_DB2000_FB_VDD
L10  Q_INDUCTOR  BLM18PG121SN1D/2000MA EMPTY  pkg SMLF  page 189 : 1 = P1V8_PCH_AUX ; 2 = P1V8_PCH_PLL_AUX
L13  Q_INDUCTOR  FCM2012KF-601T/0.5A IND  pkg SMLF  page 210 : 1 = P3V3_AUX ; 2 = P3V3_AUX_CLK_GEN_VDDXTAL_CK440
L14  Q_INDUCTOR  FCM2012KF-601T/0.5A IND  pkg SMLF  page 210 : 1 = P3V3_AUX ; 2 = P3V3_AUX_CLK_GEN_VDDMXCK_CK440
L15  Q_INDUCTOR  BLM18PG300SN1D EMPTY  pkg SMLF  page 250 : 1 = P3V3_MAX11617_VDD ; 2 = P3V3_AUX
L16  Q_INDUCTOR  BLM18PG300SN1D IND  pkg SMLF  page 250 : 1 = P3V3_AUX ; 2 = P3V3_ADC128_VCC
L17  Q_INDUCTOR  FCM2012KF-601T/0.5A IND  pkg SMLF  page 212 : 1 = P3V3_AUX ; 2 = VFG3P3_CLK_GEN
L18  Q_INDUCTOR  BLM15PX121SN1D/2A IND  pkg SMLF  page 169 : 1 = P3V3_AUX ; 2 = P3V3_AUX_USB_BUF
L19  Q_INDUCTOR  FCM2012KF-601T/0.5A IND  pkg SMLF  page 211 : 1 = P3V3 ; 2 = P3V3_9ZXL045
L20  Q_INDUCTOR  FCM2012KF-601T/0.5A IND  pkg SMLF  page 211 : 1 = P3V3 ; 2 = P3V3_9ZXL045_VDD
ME2  ME_DUMMY_SYMBOL  PICKUP_SMDC20 EMPTY  pkg PICKUP_SMDC20  page 312
ME3  ME_DUMMY_SYMBOL  PICKUP_SMDC20 EMPTY  pkg PICKUP_SMDC20  page 312
ME4  ME_DUMMY_SYMBOL  PICKUP_SMDC20 EMPTY  pkg PICKUP_SMDC20  page 312
ME9  ME_DUMMY_SYMBOL  PICKUP_SMDC20 EMPTY  pkg PICKUP_SMDC20  page 312
ME10  ME_DUMMY_SYMBOL  PICKUP_SMDC20 EMPTY  pkg PICKUP_SMDC20  page 312
ME11  ME_DUMMY_SYMBOL  PICKUP_SMDC20 EMPTY  pkg PICKUP_SMDC20  page 312
ME12  ME_DUMMY_SYMBOL  PICKUP_SMDC20 EMPTY  pkg PICKUP_SMDC20  page 312
ME13  ME_DUMMY_SYMBOL  PICKUP_SMDC20 EMPTY  pkg PICKUP_SMDC20  page 312
ME14  ME_DUMMY_SYMBOL  PICKUP_SMDC20 EMPTY  pkg PICKUP_SMDC20  page 312
ME15  ME_DUMMY_SYMBOL  PICKUP_SMDC20 EMPTY  pkg PICKUP_SMDC20  page 312
ME17  ME_DUMMY_SYMBOL  QUANTA_LOGO_7X26 EMPTY  pkg QUANTA_LOGO_7X26  page 312
ME18  ME_DUMMY_SYMBOL  WEEE EMPTY  pkg WEEE  page 312
ME20  ME_DUMMY_SYMBOL  PB-E1_SMALL EMPTY  pkg PB-E1_SMALL  page 312
ME21  ME_DUMMY_SYMBOL  PCB_VENDOR_LOGO_15X8 EMPTY  pkg PCB_VENDOR_LOGO_15X8  page 312
ME22  ME_DUMMY_SYMBOL  SNLABEL_27X6 EMPTY  pkg SNLABEL_27X6  page 312
ME27  ME_DUMMY_SYMBOL  CBS_3X558-8 EMPTY  pkg CBS_3X558-8  page 312
ME28  ME_DUMMY_SYMBOL  EFI BIOS LABEL EMPTY  pkg BIOS-BMCLABEL_10-5X10-5  page 312
ME29  ME_DUMMY_SYMBOL  SNLABEL_15X5 EMPTY  pkg SNLABEL_15X5  page 312

OSC1  Q_OSC4P  50MHZ OSC  pkg SMLF  page 155
  1  OE  IN  = CLK_50M_EN
  2  GND  POWER  = GND
  3  \out\  OUT  = CLK_50M_RMII
  4  VDD  POWER  = P3V3_AUX

OSC2  Q_OSC4P  25MHZ OSC  pkg SMLF  page 214
  1  OE  IN  = PU_CLK25M_OSC_FPGA_EN
  2  GND  POWER  = GND
  3  \out\  OUT  = CLK_25M_OSC_FPGA_R
  4  VDD  POWER  = P3V3_AUX

PC1  Q_CAP  22UF 4V 20% X6S  pkg C0805  page 279 : 1 = PVCCD_HV_CPU0 ; 2 = GND
PC2  Q_CAP  22UF 4V 20% X6S  pkg C0805  page 297 : 1 = PVCCD_HV_CPU1 ; 2 = GND
PC3  Q_CAPP  270UF 16V 20% OSCON  pkg THLF  page 259 : 1 = SW_P3V3_AUX_FLT ; 2 = GND
PC8  Q_CAP  4.7UF 16V 10% X6S  pkg C0603  page 259 : 1 = P12V_AUX ; 2 = GND
PC16  Q_CAPP  560UF 2.5V 20% OSCON  pkg THLF  page 267 : 1 = PVCCIN_CPU0 ; 2 = GND
PC27  Q_CAP  3300PF 50V 10% X7R  pkg 0402  page 282 : 1 = PVNN_MAIN_CPU0_REF ; 2 = GND
PC28  Q_CAP  3300PF 50V 10% X7R  pkg 0402  page 300 : 1 = PVNN_MAIN_CPU1_REF ; 2 = GND
PC71  Q_CAP  22UF 16V 20% X6S  pkg C0805  page 259 : 1 = SW_P3V3_AUX_FLT ; 2 = GND
PC83  Q_CAPP  560UF 2.5V 20% OSCON  pkg THLF  page 285 : 1 = PVCCIN_CPU1 ; 2 = GND
PC100  Q_CAP  470PF 50V 10% X7R  pkg 0402  page 266 : 1 = PVCCFA_EHV_FIVRA_CPU0_BTSEN ; 2 = GND
PC101  Q_CAP  470PF 50V 10% X7R  pkg 0402  page 284 : 1 = PVCCFA_EHV_FIVRA_CPU1_BTSEN ; 2 = GND
PC113  Q_CAP  1UF 25V 10% X6S  pkg C0402  page 262 : 1 = P1V05_PCH_AUX_VCC ; 2 = GND
PC117  Q_CAPP  330UF 2V 35% SPCAP  pkg SMLF  page 262 : 1 = P1V05_PCH_AUX ; 2 = GND
PC175  Q_CAP  2.2UF 10V 10% X6S  pkg C0402  page 276 : 1 = PVCCFA_EHV_CPU0_VDD1 ; 2 = GND
PC176  Q_CAP  3300PF 50V 10% X7R  pkg 0402  page 276 : 1 = SW_P12V_PVCCINFAON_CPU0_FLT ; 2 = GND
PC177  Q_CAP  1UF 16V 10% X6S  pkg C0402  page 276 : 1 = SW_P12V_PVCCINFAON_CPU0_FLT ; 2 = GND
PC178  Q_CAP  100NF 50V 10% X7R  pkg C0402  page 276 : 1 = SW_PVCCFA_EHV_CPU0_BOOT1_R ; 2 = SW_PVCCFA_EHV_CPU0_BOOTR1
PC179  Q_CAP  22UF 16V 20% X6S  pkg C0805  page 276 : 1 = SW_P12V_PVCCINFAON_CPU0_FLT ; 2 = GND
PC180  Q_CAP  22UF 16V 20% X6S  pkg C0805  page 276 : 1 = SW_P12V_PVCCINFAON_CPU0_FLT ; 2 = GND
PC181  Q_CAP  100NF 50V 10% X7R  pkg C0402  page 276 : 1 = PVCCFA_EHV_CPU0 ; 2 = GND
PC184  Q_CAP  22UF 4V 20% X6S  pkg C0805  page 276 : 1 = PVCCFA_EHV_CPU0 ; 2 = GND
PC186  Q_CAP  22UF 4V 20% X6S  pkg C0805  page 276 : 1 = PVCCFA_EHV_CPU0 ; 2 = GND
PC187  Q_CAP  2.2UF 10V 10% X6S  pkg C0402  page 275 : 1 = PVCCINFAON_CPU0_VDD1 ; 2 = GND
PC188  Q_CAP  2.2UF 10V 10% X6S  pkg C0402  page 275 : 1 = PVCCINFAON_CPU0_VDD2 ; 2 = GND
PC189  Q_CAPP  330UF 2.5V +10/-35% EMPTY  pkg SMLF  page 285 : 1 = PVCCIN_CPU1 ; 2 = GND
PC189_P0_1  Q_CAP  3300PF 50V 10% X7R  pkg 0402  page 275 : 1 = SW_P12V_PVCCINFAON_CPU0_FLT ; 2 = GND
PC190  Q_CAP  1UF 25V 10% X6S  pkg C0402  page 162 : 1 = P3V3_OCP_VCC_2 ; 2 = GND
PC190_P0_2  Q_CAP  3300PF 50V 10% X7R  pkg 0402  page 275 : 1 = SW_P12V_PVCCINFAON_CPU0_FLT ; 2 = GND
PC191_P0_1  Q_CAP  1UF 16V 10% X6S  pkg C0402  page 275 : 1 = SW_P12V_PVCCINFAON_CPU0_FLT ; 2 = GND
PC192_P0_2  Q_CAP  1UF 16V 10% X6S  pkg C0402  page 275 : 1 = SW_P12V_PVCCINFAON_CPU0_FLT ; 2 = GND
PC193  Q_CAP  100NF 50V 10% X7R  pkg C0402  page 275 : 1 = SW_PVCCINFAON_CPU0_BOOT1_R ; 2 = SW_PVCCINFAON_CPU0_BOOTR1
PC194  Q_CAP  100NF 50V 10% X7R  pkg C0402  page 275 : 1 = SW_PVCCINFAON_CPU0_BOOT2_R ; 2 = SW_PVCCINFAON_CPU0_BOOTR2
PC195_P0_1  Q_CAP  22UF 16V 20% X6S  pkg C0805  page 275 : 1 = SW_P12V_PVCCINFAON_CPU0_FLT ; 2 = GND
PC196_P0_2  Q_CAP  22UF 16V 20% X6S  pkg C0805  page 275 : 1 = SW_P12V_PVCCINFAON_CPU0_FLT ; 2 = GND
